FILE_TYPE = CONNECTIVITY;
{Allegro Design Entry HDL 17.4-2019 S026 (4007227) 1/17/2022}
"PAGE_NUMBER" = 173;
0"NC";
1"GND\g";
2"GND\g";
3"GND\g";
4"GND\g";
5"GND\g";
6"GND\g";
7"GND\g";
8"GND\g";
9"GND\g";
10"GND\g";
11"GND\g";
12"PVDDCR_CPU0_P0_PVCC\g";
13"GND\g";
14"PVDDCR_CPU0_P0_PVCC\g";
15"GND\g";
16"GND\g";
17"SW_P12V_AUX_PVDDCR_SOC_P0_FLT\g";
18"GND\g";
19"PVDDCR_SOC_P0\g";
20"GND\g";
21"PVDDCR_SOC_P0\g";
22"GND\g";
23"SW_P12V_AUX_PVDDCR_SOC_P0_FLT\g";
24"GND\g";
25"P12V_AUX\g";
26"GND\g";
27"PVDDCR_SOC_P0\g";
28"PVDDCR_SOC_P0_IMON1";
29"PVDDCR_SOC_P0_VCC1";
30"SW_PVDDCR_SOC_P0_PH1";
31"SW_PVDDCR_SOC_P0_SW1";
32"SW_PVDDCR_SOC_P0_BOOT1";
33"PVDDCR_SOC_P0_VOS1";
34"SW_PVDDCR_SOC_P0_SW1_RC";
35"SW_PVDDCR_SOC_P0_BOOT1_RC";
36"SW_PVDDCR_SOC_P0_BOOT2";
37"SW_PVDDCR_SOC_P0_BOOT2_RC";
38"PVDDCR_CPU0_P0_VCCS";
39"PVDDCR_SOC_P0_VCC2";
40"SW_PVDDCR_SOC_P0_PH2";
41"SW_PVDDCR_SOC_P0_SW2";
42"NC_PVDDCR_SOC_P0_DNC2";
43"PVDDCR_SOC_P0_LSET2";
44"PVDDCR_SOC_P0_IMON2";
45"IND_SOC_P0_CPL2";
46"IND_SOC_P0_CPL2";
47"IND_SOC_P0_CPL3";
48"NC_PVDDCR_SOC_P0_GL1_1";
49"NC_PVDDCR_SOC_P0_GL2_1";
50"PVDDCR_SOC_P0_LSET1";
51"PVDDCR_SOC_P0_PWM1";
52"PVDDCR_SOC_P0_TEMP1";
53"NC_PVDDCR_SOC_P0_DNC1";
54"PVDDCR_CPU0_P0_VCCS";
55"SW_PVDDCR_SOC_P0_SW2_RC";
56"PVDDCR_SOC_P0_VOS2";
57"NC_PVDDCR_SOC_P0_GL1_2";
58"NC_PVDDCR_SOC_P0_GL2_2";
59"PVDDCR_SOC_P0_PWM2";
60"PVDDCR_SOC_P0_TEMP1";
%"Q_CAP"
"1","(-7300,2325)","0","pure_quanta","I11";
;
LOCATION"PC580"
$SEC"1"
CDS_SEC"1"
PACK_TYPE"C0402"
VALUE"2.2UF"
VOLTAGE"10V"
TOLERANCE"10%"
MATERIAL"X6S"
PART_NUMBER"CH5222KEB01"
CDS_LIB"pure_quanta";
"B"
$PN"2"11;
"A"
$PN"1"39;
%"Q_RES"
"2","(-7300,2850)","0","pure_quanta","I12";
;
LOCATION"PR357"
$SEC"1"
CDS_SEC"1"
WATTAGE"1/16W"
MATERIAL"CHIP"
TOLERANCE"1%"
VALUE"2.2"
PACK_TYPE"0402LF"
PART_NUMBER"CS-2202FB01"
CDS_LIB"pure_quanta";
"A"
$PN"1"12;
"B"
$PN"2"39;
%"VCC_CORE"
"1","(-7300,3250)","0","pure_quanta_power","I13";
;
HDL_POWER"PVDDCR_CPU0_P0_PVCC"
CDS_LIB"pure_quanta_power";
"A"12;
%"Q_CAP"
"1","(-6950,2850)","0","pure_quanta","I14";
;
LOCATION"PC582_SOP0_2"
$SEC"1"
CDS_SEC"1"
TOLERANCE"10%"
MATERIAL"X6S"
PACK_TYPE"C0402"
VOLTAGE"10V"
VALUE"2.2UF"
PART_NUMBER"CH5222KEB01"
CDS_LIB"pure_quanta";
"B"
$PN"2"1;
"A"
$PN"1"12;
%"UNIVERSAL_GND"
"1","(-6950,2600)","0","pure_quanta_power","I15";
;
HDL_POWER"GND"
CDS_LIB"pure_quanta_power";
"A"1;
%"UNIVERSAL_GND"
"1","(-5225,1275)","0","pure_quanta_power","I16";
;
HDL_POWER"GND"
CDS_LIB"pure_quanta_power";
"A"13;
%"UNIVERSAL_GND"
"1","(-4500,1075)","0","pure_quanta_power","I17";
;
HDL_POWER"GND"
CDS_LIB"pure_quanta_power";
"A"2;
%"Q_RES"
"1","(-4025,975)","0","pure_quanta","I18";
;
LOCATION"PR363"
$SEC"1"
CDS_SEC"1"
WATTAGE"1/16W"
TOLERANCE"5%"
MATERIAL"CHIP"
VALUE"0"
PACK_TYPE"0402LF"
PART_NUMBER"CS00002JB13"
CDS_LIB"pure_quanta";
"B"
$PN"2"19;
"A"
$PN"1"56;
%"Q_RES"
"2","(-4500,1300)","0","pure_quanta","I19";
;
LOCATION"PR503"
$SEC"1"
CDS_SEC"1"
PACK_TYPE"0402LF"
VALUE"1.5"
TOLERANCE"1%"
MATERIAL"EMPTY"
WATTAGE"1/8W"
PART_NUMBER"CS-1504FB00"
CDS_LIB"pure_quanta";
"A"
$PN"1"55;
"B"
$PN"2"2;
%"Q_CAP"
"1","(-5150,2875)","0","pure_quanta","I21";
;
LOCATION"PC586_2"
$SEC"1"
CDS_SEC"1"
MATERIAL"X7R"
TOLERANCE"10%"
PACK_TYPE"0402"
VOLTAGE"25V"
VALUE"0.1UF"
PART_NUMBER"CH4104K1B00"
CDS_LIB"pure_quanta";
"B"
$PN"2"16;
"A"
$PN"1"17;
%"Q_RES"
"1","(-4475,2325)","0","pure_quanta","I22";
;
LOCATION"PR361"
$SEC"1"
CDS_SEC"1"
TOLERANCE"1%"
PACK_TYPE"0402LF"
WATTAGE"1/16W"
MATERIAL"CHIP"
VALUE"5.6"
PART_NUMBER"CS-5602FB01"
CDS_LIB"pure_quanta";
"B"
$PN"2"37;
"A"
$PN"1"36;
%"Q_CAP"
"1","(-4775,2875)","0","pure_quanta","I23";
;
LOCATION"PC584_2"
$SEC"1"
CDS_SEC"1"
VOLTAGE"25V"
PACK_TYPE"C0402"
MATERIAL"X6S"
VALUE"1UF"
TOLERANCE"10%"
PART_NUMBER"CH5104KEB02"
CDS_LIB"pure_quanta";
"B"
$PN"2"16;
"A"
$PN"1"17;
%"Q_CAP"
"1","(-4450,2875)","0","pure_quanta","I24";
;
LOCATION"PC588_2"
$SEC"1"
CDS_SEC"1"
MATERIAL"X6S"
TOLERANCE"20%"
VOLTAGE"16V"
VALUE"22UF"
PACK_TYPE"C0805"
PART_NUMBER"CH6223MEA01"
CDS_LIB"pure_quanta";
"B"
$PN"2"16;
"A"
$PN"1"17;
%"Q_CAP"
"1","(-4125,2875)","0","pure_quanta","I25";
;
LOCATION"PC590_2"
$SEC"1"
CDS_SEC"1"
VOLTAGE"16V"
TOLERANCE"20%"
MATERIAL"X6S"
PACK_TYPE"C0805"
VALUE"22UF"
PART_NUMBER"CH6223MEA01"
CDS_LIB"pure_quanta";
"B"
$PN"2"16;
"A"
$PN"1"17;
%"UNIVERSAL_GND"
"1","(-4475,4125)","0","pure_quanta_power","I26";
;
HDL_POWER"GND"
CDS_LIB"pure_quanta_power";
"A"3;
%"Q_RES"
"1","(-4000,3900)","0","pure_quanta","I27";
;
LOCATION"PR362"
$SEC"1"
CDS_SEC"1"
PACK_TYPE"0402LF"
TOLERANCE"5%"
WATTAGE"1/16W"
MATERIAL"CHIP"
VALUE"0"
PART_NUMBER"CS00002JB13"
CDS_LIB"pure_quanta";
"B"
$PN"2"27;
"A"
$PN"1"33;
%"UNIVERSAL_GND"
"1","(-7650,4525)","0","pure_quanta_power","I28";
;
HDL_POWER"GND"
CDS_LIB"pure_quanta_power";
"A"4;
%"Q_CAP"
"1","(-7650,4800)","0","pure_quanta","I29";
;
LOCATION"PC577_7"
$SEC"1"
CDS_SEC"1"
VOLTAGE"25V"
PACK_TYPE"0402"
MATERIAL"X7R"
TOLERANCE"10%"
VALUE"0.1UF"
PART_NUMBER"CH4104K1B00"
CDS_LIB"pure_quanta";
"B"
$PN"2"4;
"A"
$PN"1"54;
%"UNIVERSAL_GND"
"1","(-7625,1425)","0","pure_quanta_power","I3";
;
HDL_POWER"GND"
CDS_LIB"pure_quanta_power";
"A"5;
%"UNIVERSAL_GND"
"1","(-7325,4600)","0","pure_quanta_power","I30";
;
HDL_POWER"GND"
CDS_LIB"pure_quanta_power";
"A"6;
%"Q_RES"
"1","(-7000,4775)","0","pure_quanta","I32";
;
LOCATION"PR358"
$SEC"1"
CDS_SEC"1"
TOLERANCE"1%"
PACK_TYPE"0402LF"
WATTAGE"1/16W"
MATERIAL"EMPTY"
VALUE"8.87K"
PART_NUMBER"CS28872FB01"
CDS_LIB"pure_quanta";
"B"
$PN"2"50;
"A"
$PN"1"6;
%"UNIVERSAL_GND"
"1","(-7325,5225)","0","pure_quanta_power","I34";
;
HDL_POWER"GND"
CDS_LIB"pure_quanta_power";
"A"7;
%"Q_CAP"
"1","(-7325,5425)","0","pure_quanta","I36";
;
LOCATION"PC579"
$SEC"1"
CDS_SEC"1"
TOLERANCE"10%"
MATERIAL"X6S"
PACK_TYPE"C0402"
VOLTAGE"10V"
VALUE"2.2UF"
PART_NUMBER"CH5222KEB01"
CDS_LIB"pure_quanta";
"B"
$PN"2"7;
"A"
$PN"1"29;
%"UNIVERSAL_GND"
"1","(-6975,5675)","0","pure_quanta_power","I37";
;
HDL_POWER"GND"
CDS_LIB"pure_quanta_power";
"A"8;
%"Q_RES"
"2","(-7325,5925)","0","pure_quanta","I38";
;
LOCATION"PR356"
$SEC"1"
CDS_SEC"1"
VALUE"2.2"
WATTAGE"1/16W"
MATERIAL"CHIP"
TOLERANCE"1%"
PACK_TYPE"0402LF"
PART_NUMBER"CS-2202FB01"
CDS_LIB"pure_quanta";
"A"
$PN"1"14;
"B"
$PN"2"29;
%"VCC_CORE"
"1","(-7325,6325)","0","pure_quanta_power","I39";
;
HDL_POWER"PVDDCR_CPU0_P0_PVCC"
CDS_LIB"pure_quanta_power";
"A"14;
%"Q_CAP"
"1","(-7625,1700)","0","pure_quanta","I4";
;
LOCATION"PC578_8"
$SEC"1"
CDS_SEC"1"
TOLERANCE"10%"
VOLTAGE"25V"
VALUE"0.1UF"
MATERIAL"X7R"
PACK_TYPE"0402"
PART_NUMBER"CH4104K1B00"
CDS_LIB"pure_quanta";
"B"
$PN"2"5;
"A"
$PN"1"38;
%"Q_CAP"
"1","(-6975,5925)","0","pure_quanta","I40";
;
LOCATION"PC581_SOP0_1"
$SEC"1"
CDS_SEC"1"
TOLERANCE"10%"
MATERIAL"X6S"
PACK_TYPE"C0402"
VOLTAGE"10V"
VALUE"2.2UF"
PART_NUMBER"CH5222KEB01"
CDS_LIB"pure_quanta";
"B"
$PN"2"8;
"A"
$PN"1"14;
%"ISL99390FRZTR5935"
"1","(-5825,5075)","0","pure_quanta","I41";
;
LOCATION"PU49"
$SEC"1"
CDS_SEC"1"
VALUE"ISL99390FRZ-TR5935"
PART_TYPE"SMLF"
MATERIAL"IC"
PART_NUMBER"AL099390004"
CDS_LIB"pure_quanta"
NEEDS_NO_SIZE"TRUE"
CDS_LMAN_SYM_OUTLINE"-300,700,250,-650";
"PGND2"
$PN"7_9-20_24"15;
"GL2"
$PN"41"49;
"GL1"
$PN"6"48;
"DNC"
$PN"31"53;
"EN"
$PN"35"29;
"PGND3"
$PN"40"15;
"VOS"
$PN"1"33;
"VIN2"
$PN"30"23;
"PGND1"
$PN"5"15;
"SW"
$PN"10_19"31;
"LSET"
$PN"37"50;
"IOUT"
$PN"38"28;
"TOUT_FLT"
$PN"36"52;
"PVCC"
$PN"4"14;
"PHASE"
$PN"32"30;
"VIN1"
$PN"25_29"23;
"BOOT"
$PN"33"32;
"AGND"
$PN"2"15;
"VCC"
$PN"3"29;
"REFIN"
$PN"39"54;
"PWM"
$PN"34"51;
%"UNIVERSAL_GND"
"1","(-5250,4350)","0","pure_quanta_power","I42";
;
HDL_POWER"GND"
CDS_LIB"pure_quanta_power";
"A"15;
%"Q_CAP"
"1","(-5225,5925)","0","pure_quanta","I43";
;
LOCATION"PC583_1"
$SEC"1"
CDS_SEC"1"
PACK_TYPE"0402"
TOLERANCE"10%"
MATERIAL"X7R"
VALUE"0.1UF"
VOLTAGE"25V"
PART_NUMBER"CH4104K1B00"
CDS_LIB"pure_quanta";
"B"
$PN"2"22;
"A"
$PN"1"23;
%"Q_CAP"
"1","(-4900,5925)","0","pure_quanta","I44";
;
LOCATION"PC585_1"
$SEC"1"
CDS_SEC"1"
VALUE"1UF"
PACK_TYPE"C0402"
MATERIAL"X6S"
TOLERANCE"10%"
VOLTAGE"25V"
PART_NUMBER"CH5104KEB02"
CDS_LIB"pure_quanta";
"B"
$PN"2"22;
"A"
$PN"1"23;
%"Q_RES"
"2","(-4475,4375)","0","pure_quanta","I45";
;
LOCATION"PR502"
$SEC"1"
CDS_SEC"1"
PACK_TYPE"0402LF"
MATERIAL"EMPTY"
WATTAGE"1/8W"
VALUE"1.5"
TOLERANCE"1%"
PART_NUMBER"CS-1504FB00"
CDS_LIB"pure_quanta";
"A"
$PN"1"34;
"B"
$PN"2"3;
%"Q_CAP"
"1","(-4475,4825)","0","pure_quanta","I46";
;
LOCATION"PC185"
$SEC"1"
CDS_SEC"1"
MATERIAL"EMPTY"
PACK_TYPE"C0402"
VALUE"560PF"
TOLERANCE"10%"
VOLTAGE"50V"
PART_NUMBER"CH1566K1B09"
CDS_LIB"pure_quanta";
"B"
$PN"2"34;
"A"
$PN"1"31;
%"Q_RES"
"1","(-4525,5425)","0","pure_quanta","I48";
;
LOCATION"PR360"
$SEC"1"
CDS_SEC"1"
MATERIAL"CHIP"
TOLERANCE"1%"
VALUE"5.6"
PACK_TYPE"0402LF"
WATTAGE"1/16W"
PART_NUMBER"CS-5602FB01"
CDS_LIB"pure_quanta";
"B"
$PN"2"35;
"A"
$PN"1"32;
%"Q_CAP"
"1","(-4575,5925)","0","pure_quanta","I49";
;
LOCATION"PC587_1"
$SEC"1"
CDS_SEC"1"
VOLTAGE"16V"
VALUE"22UF"
TOLERANCE"20%"
MATERIAL"X6S"
PACK_TYPE"C0805"
PART_NUMBER"CH6223MEA01"
CDS_LIB"pure_quanta";
"B"
$PN"2"22;
"A"
$PN"1"23;
%"UNIVERSAL_GND"
"1","(-7300,1500)","0","pure_quanta_power","I5";
;
HDL_POWER"GND"
CDS_LIB"pure_quanta_power";
"A"9;
%"Q_CAP"
"1","(-4250,5925)","0","pure_quanta","I50";
;
LOCATION"PC589_1"
$SEC"1"
CDS_SEC"1"
VOLTAGE"16V"
TOLERANCE"20%"
VALUE"22UF"
PACK_TYPE"C0805"
MATERIAL"X6S"
PART_NUMBER"CH6223MEA01"
CDS_LIB"pure_quanta";
"B"
$PN"2"22;
"A"
$PN"1"23;
%"Q_CAP"
"1","(-4025,5925)","0","pure_quanta","I51";
;
LOCATION"PC591_1"
$SEC"1"
CDS_SEC"1"
PACK_TYPE"C0805"
MATERIAL"X6S"
VOLTAGE"16V"
TOLERANCE"20%"
VALUE"22UF"
PART_NUMBER"CH6223MEA01"
CDS_LIB"pure_quanta";
"B"
$PN"2"22;
"A"
$PN"1"23;
%"Q_CAP"
"1","(-3575,2200)","0","pure_quanta","I52";
;
LOCATION"PC594"
$SEC"1"
CDS_SEC"1"
TOLERANCE"10%"
VOLTAGE"16V"
VALUE"0.22UF"
PACK_TYPE"0402"
MATERIAL"X7R"
PART_NUMBER"CH4223K1B00"
CDS_LIB"pure_quanta";
"B"
$PN"2"40;
"A"
$PN"1"37;
%"Q_INDUCTOR4P_14"
"1","(-2825,1850)","0","pure_quanta","I53";
;
LOCATION"PL64"
$SEC"1"
CDS_SEC"1"
VALUE"150NH"
MATERIAL"IND"
PART_TYPE"SMLF"
PART_NUMBER"CV+15^0TZ04"
NEEDS_NO_SIZE"TRUE"
CDS_LIB"pure_quanta";
"1"
$PN"1"41;
"4"
$PN"4"19;
"3"
$PN"3"46;
"2"
$PN"2"47;
%"UNIVERSAL_GND"
"1","(-3400,2550)","0","pure_quanta_power","I55";
;
HDL_POWER"GND"
CDS_LIB"pure_quanta_power";
"A"16;
%"Q_CAP"
"1","(-3800,2875)","0","pure_quanta","I56";
;
LOCATION"PC592_2"
$SEC"1"
CDS_SEC"1"
VALUE"22UF"
TOLERANCE"20%"
PACK_TYPE"C0805"
MATERIAL"X6S"
VOLTAGE"16V"
PART_NUMBER"CH6223MEA01"
CDS_LIB"pure_quanta";
"B"
$PN"2"16;
"A"
$PN"1"17;
%"Q_CAP"
"1","(-3400,2875)","0","pure_quanta","I57";
;
LOCATION"PC595_2"
$SEC"1"
CDS_SEC"1"
MATERIAL"X6S"
PACK_TYPE"C0805"
VOLTAGE"16V"
VALUE"22UF"
TOLERANCE"20%"
PART_NUMBER"CH6223MEA01"
CDS_LIB"pure_quanta";
"B"
$PN"2"16;
"A"
$PN"1"17;
%"VCC_CORE"
"1","(-3400,3150)","0","pure_quanta_power","I58";
;
HDL_POWER"SW_P12V_AUX_PVDDCR_SOC_P0_FLT"
CDS_LIB"pure_quanta_power";
"A"17;
%"Q_CAP"
"1","(-1425,1800)","0","pure_quanta","I59";
;
LOCATION"PC600_2"
$SEC"1"
CDS_SEC"1"
TOLERANCE"20%"
PACK_TYPE"C0805"
MATERIAL"X6S"
VALUE"22UF"
VOLTAGE"4V"
PART_NUMBER"CH622KMEA03"
CDS_LIB"pure_quanta";
"B"
$PN"2"18;
"A"
$PN"1"19;
%"UNIVERSAL_GND"
"1","(-1000,1450)","0","pure_quanta_power","I60";
;
HDL_POWER"GND"
CDS_LIB"pure_quanta_power";
"A"18;
%"Q_CAP"
"1","(-1000,1800)","0","pure_quanta","I61";
;
LOCATION"PC603_2"
$SEC"1"
CDS_SEC"1"
TOLERANCE"20%"
PACK_TYPE"C0805"
MATERIAL"X6S"
VALUE"22UF"
VOLTAGE"4V"
PART_NUMBER"CH622KMEA03"
CDS_LIB"pure_quanta";
"B"
$PN"2"18;
"A"
$PN"1"19;
%"VCC_CORE"
"1","(-1000,2125)","0","pure_quanta_power","I62";
;
HDL_POWER"PVDDCR_SOC_P0"
CDS_LIB"pure_quanta_power";
"A"19;
%"Q_CAPP"
"1","(-1625,3250)","0","pure_quanta","I63";
;
LOCATION"PC597"
$SEC"1"
CDS_SEC"1"
PACK_TYPE"SMLF"
VOLTAGE"2.5V"
TOLERANCE"20%"
MATERIAL"EMPTY"
VALUE"470UF"
PART_NUMBER"CH747LM8825"
CDS_LIB"pure_quanta";
"A"
$PN"1"21;
"B"
$PN"2"20;
%"Q_CAPP"
"1","(-1275,3250)","0","pure_quanta","I64";
;
LOCATION"PC598"
$SEC"1"
CDS_SEC"1"
PACK_TYPE"SMLF"
MATERIAL"SPCAP"
TOLERANCE"20%"
VOLTAGE"2.5V"
VALUE"470UF"
PART_NUMBER"CH747LM8825"
CDS_LIB"pure_quanta";
"A"
$PN"1"21;
"B"
$PN"2"20;
%"UNIVERSAL_GND"
"1","(-950,2900)","0","pure_quanta_power","I65";
;
HDL_POWER"GND"
CDS_LIB"pure_quanta_power";
"A"20;
%"Q_CAPP"
"1","(-950,3250)","0","pure_quanta","I66";
;
LOCATION"PC601"
$SEC"1"
CDS_SEC"1"
PACK_TYPE"SMLF"
VOLTAGE"2.5V"
VALUE"470UF"
TOLERANCE"20%"
MATERIAL"SPCAP"
PART_NUMBER"CH747LM8825"
CDS_LIB"pure_quanta";
"A"
$PN"1"21;
"B"
$PN"2"20;
%"VCC_CORE"
"1","(-950,3525)","0","pure_quanta_power","I67";
;
HDL_POWER"PVDDCR_SOC_P0"
CDS_LIB"pure_quanta_power";
"A"21;
%"Q_CAP"
"1","(-3675,5300)","0","pure_quanta","I68";
;
LOCATION"PC593"
$SEC"1"
CDS_SEC"1"
PACK_TYPE"0402"
VALUE"0.22UF"
VOLTAGE"16V"
TOLERANCE"10%"
MATERIAL"X7R"
PART_NUMBER"CH4223K1B00"
CDS_LIB"pure_quanta";
"B"
$PN"2"30;
"A"
$PN"1"35;
%"Q_INDUCTOR4P_14"
"1","(-2900,4950)","0","pure_quanta","I69";
;
LOCATION"PL63"
$SEC"1"
CDS_SEC"1"
MATERIAL"IND"
PART_TYPE"SMLF"
VALUE"150NH"
PART_NUMBER"CV+15^0TZ04"
NEEDS_NO_SIZE"TRUE"
CDS_LIB"pure_quanta";
"1"
$PN"1"31;
"4"
$PN"4"27;
"3"
$PN"3"24;
"2"
$PN"2"45;
%"UNIVERSAL_GND"
"1","(-3675,5600)","0","pure_quanta_power","I70";
;
HDL_POWER"GND"
CDS_LIB"pure_quanta_power";
"A"22;
%"VCC_CORE"
"1","(-3675,6200)","0","pure_quanta_power","I71";
;
HDL_POWER"SW_P12V_AUX_PVDDCR_SOC_P0_FLT"
CDS_LIB"pure_quanta_power";
"A"23;
%"Q_CAP"
"1","(-3800,5925)","0","pure_quanta","I72";
;
LOCATION"PC593_1"
$SEC"1"
CDS_SEC"1"
VALUE"22UF"
TOLERANCE"20%"
VOLTAGE"16V"
PACK_TYPE"C0805"
MATERIAL"X6S"
PART_NUMBER"CH6223MEA01"
CDS_LIB"pure_quanta";
"B"
$PN"2"22;
"A"
$PN"1"23;
%"Q_CAPP"
"1","(-3225,5925)","0","pure_quanta","I73";
;
LOCATION"PC596"
$SEC"1"
CDS_SEC"1"
TOLERANCE"20%"
VALUE"270UF"
MATERIAL"OSCON"
PACK_TYPE"THLF"
VOLTAGE"16V"
PART_NUMBER"CC72703MD38"
CDS_LIB"pure_quanta";
"A"
$PN"1"23;
"B"
$PN"2"22;
%"Q_INDUCTOR"
"1","(-2775,6125)","0","pure_quanta","I74";
;
LOCATION"PL65"
$SEC"1"
CDS_SEC"1"
MATERIAL"IND"
VALUE"50NH/86A"
PACK_TYPE"SMLF"
PART_NUMBER"CVA50^0MZ09"
NEEDS_NO_SIZE"TRUE"
CDS_LIB"pure_quanta";
"1"
$PN"1"23;
"2"
$PN"2"25;
%"UNIVERSAL_GND"
"1","(-2025,4675)","0","pure_quanta_power","I75";
;
HDL_POWER"GND"
CDS_LIB"pure_quanta_power";
"A"24;
%"UNIVERSAL_GND"
"1","(-2375,5625)","0","pure_quanta_power","I76";
;
HDL_POWER"GND"
CDS_LIB"pure_quanta_power";
"A"10;
%"Q_CAP"
"1","(-2375,5950)","0","pure_quanta","I77";
;
LOCATION"PC583"
$SEC"1"
CDS_SEC"1"
VOLTAGE"25V"
TOLERANCE"10%"
MATERIAL"X7R"
PACK_TYPE"0402"
VALUE"0.1UF"
PART_NUMBER"CH4104K1B00"
CDS_LIB"pure_quanta";
"B"
$PN"2"10;
"A"
$PN"1"25;
%"VCC_CORE"
"1","(-2375,6200)","0","pure_quanta_power","I78";
;
HDL_POWER"P12V_AUX"
CDS_LIB"pure_quanta_power";
"A"25;
%"Q_CAP"
"1","(-1500,4900)","0","pure_quanta","I79";
;
LOCATION"PC599"
$SEC"1"
CDS_SEC"1"
TOLERANCE"10%"
VOLTAGE"25V"
VALUE"0.1UF"
PACK_TYPE"0402"
MATERIAL"X7R"
PART_NUMBER"CH4104K1B00"
CDS_LIB"pure_quanta";
"B"
$PN"2"26;
"A"
$PN"1"27;
%"Q_RES"
"1","(-6950,1675)","0","pure_quanta","I8";
;
LOCATION"PR359"
$SEC"1"
CDS_SEC"1"
WATTAGE"1/16W"
MATERIAL"EMPTY"
PACK_TYPE"0402LF"
VALUE"8.87K"
TOLERANCE"1%"
PART_NUMBER"CS28872FB01"
CDS_LIB"pure_quanta";
"B"
$PN"2"43;
"A"
$PN"1"9;
%"Q_CAP"
"1","(-1125,4900)","0","pure_quanta","I80";
;
LOCATION"PC602_1"
$SEC"1"
CDS_SEC"1"
PACK_TYPE"C0805"
MATERIAL"X6S"
TOLERANCE"20%"
VALUE"22UF"
VOLTAGE"4V"
PART_NUMBER"CH622KMEA03"
CDS_LIB"pure_quanta";
"B"
$PN"2"26;
"A"
$PN"1"27;
%"UNIVERSAL_GND"
"1","(-350,4475)","0","pure_quanta_power","I81";
;
HDL_POWER"GND"
CDS_LIB"pure_quanta_power";
"A"26;
%"Q_RES"
"2","(-350,4875)","0","pure_quanta","I82";
;
LOCATION"PR334"
$SEC"1"
CDS_SEC"1"
WATTAGE"1/16W"
MATERIAL"CHIP"
TOLERANCE"1%"
VALUE"1K"
PACK_TYPE"0402LF"
PART_NUMBER"CS21002FB06"
CDS_LIB"pure_quanta";
"A"
$PN"1"27;
"B"
$PN"2"26;
%"Q_CAP"
"1","(-675,4900)","0","pure_quanta","I83";
;
LOCATION"PC604_1"
$SEC"1"
CDS_SEC"1"
PACK_TYPE"C0805"
MATERIAL"X6S"
TOLERANCE"20%"
VALUE"22UF"
VOLTAGE"4V"
PART_NUMBER"CH622KMEA03"
CDS_LIB"pure_quanta";
"B"
$PN"2"26;
"A"
$PN"1"27;
%"VCC_CORE"
"1","(-350,5200)","0","pure_quanta_power","I84";
;
HDL_POWER"PVDDCR_SOC_P0"
CDS_LIB"pure_quanta_power";
"A"27;
%"Q_CAP"
"1","(-4500,1800)","0","pure_quanta","I85";
;
LOCATION"PC187"
$SEC"1"
CDS_SEC"1"
TOLERANCE"10%"
PACK_TYPE"C0402"
VOLTAGE"50V"
VALUE"560PF"
MATERIAL"EMPTY"
PART_NUMBER"CH1566K1B09"
CDS_LIB"pure_quanta";
"B"
$PN"2"55;
"A"
$PN"1"41;
%"ISL99390FRZTR5935"
"1","(-5800,1975)","0","pure_quanta","I86";
;
LOCATION"PU50"
$SEC"1"
CDS_SEC"1"
VALUE"ISL99390FRZ-TR5935"
PART_TYPE"SMLF"
MATERIAL"IC"
PART_NUMBER"AL099390004"
CDS_LIB"pure_quanta"
NEEDS_NO_SIZE"TRUE"
CDS_LMAN_SYM_OUTLINE"-300,700,250,-650";
"PGND2"
$PN"7_9-20_24"13;
"GL2"
$PN"41"58;
"GL1"
$PN"6"57;
"DNC"
$PN"31"42;
"EN"
$PN"35"39;
"PGND3"
$PN"40"13;
"VOS"
$PN"1"56;
"VIN2"
$PN"30"17;
"PGND1"
$PN"5"13;
"SW"
$PN"10_19"41;
"LSET"
$PN"37"43;
"IOUT"
$PN"38"44;
"TOUT_FLT"
$PN"36"60;
"PVCC"
$PN"4"12;
"PHASE"
$PN"32"40;
"VIN1"
$PN"25_29"17;
"BOOT"
$PN"33"36;
"AGND"
$PN"2"13;
"VCC"
$PN"3"39;
"REFIN"
$PN"39"38;
"PWM"
$PN"34"59;
%"Q_CAP"
"1","(-3550,5925)","0","pure_quanta","I87";
;
LOCATION"PC8009"
$SEC"1"
CDS_SEC"1"
PACK_TYPE"C0805"
MATERIAL"X6S"
TOLERANCE"20%"
VOLTAGE"16V"
VALUE"22UF"
PART_NUMBER"CH6223MEA01"
CDS_LIB"pure_quanta";
"B"
$PN"2"22;
"A"
$PN"1"23;
%"Q_CAP"
"1","(-3075,2850)","0","pure_quanta","I88";
;
LOCATION"PC8010"
$SEC"1"
CDS_SEC"1"
TOLERANCE"20%"
PACK_TYPE"C0805"
MATERIAL"X6S"
VALUE"22UF"
VOLTAGE"16V"
PART_NUMBER"CH6223MEA01"
CDS_LIB"pure_quanta";
"B"
$PN"2"16;
"A"
$PN"1"17;
%"UNIVERSAL_GND"
"1","(-7300,2125)","0","pure_quanta_power","I9";
;
HDL_POWER"GND"
CDS_LIB"pure_quanta_power";
"A"11;
END.
